(kicad_pcb
	(version 20260206)
	(generator "pcbnew")
	(generator_version "10.0")
	(general
		(thickness 1.6)
		(legacy_teardrops no)
	)
	(paper "A4")
	(title_block
		(title "04192023_DAF0TMB3IC0_F0TG_MB_C_brd_V02_OCP.brd")
		(comment 1 "Grand Teton / footprint 4555 of 8354 (J99), pads 1-113 of 291")
	)
	(layers
		(0 "F.Cu" signal "TOP")
		(4 "In1.Cu" signal "GND")
		(6 "In2.Cu" signal "IN1")
		(8 "In3.Cu" signal "GND1")
		(10 "In4.Cu" signal "IN2")
		(12 "In5.Cu" signal "GND2")
		(14 "In6.Cu" signal "IN3")
		(16 "In7.Cu" signal "GND3")
		(18 "In8.Cu" signal "VCC")
		(20 "In9.Cu" signal "VCC1")
		(22 "In10.Cu" signal "GND4")
		(24 "In11.Cu" signal "IN4")
		(26 "In12.Cu" signal "GND5")
		(28 "In13.Cu" signal "IN5")
		(30 "In14.Cu" signal "GND6")
		(32 "In15.Cu" signal "IN6")
		(34 "In16.Cu" signal "GND7")
		(2 "B.Cu" signal "BOTTOM")
		(9 "F.Adhes" user "F.Adhesive")
		(11 "B.Adhes" user "B.Adhesive")
		(13 "F.Paste" user "Package Geometry/Pastemask Top")
		(15 "B.Paste" user "Package Geometry/Pastemask Bottom")
		(5 "F.SilkS" user "Ref Des/Silkscreen Top")
		(7 "B.SilkS" user "Ref Des/Silkscreen Bottom")
		(1 "F.Mask" user "Board Geometry/Soldermask Top")
		(3 "B.Mask" user "Board Geometry/Soldermask Bottom")
		(17 "Dwgs.User" user "User.Drawings")
		(19 "Cmts.User" user "User.Comments")
		(21 "Eco1.User" user "User.Eco1")
		(23 "Eco2.User" user "User.Eco2")
		(25 "Edge.Cuts" user "Board Geometry/Outline")
		(27 "Margin" user)
		(31 "F.CrtYd" user "Package Geometry/Place Bound Top")
		(29 "B.CrtYd" user "Package Geometry/Place Bound Bottom")
		(35 "F.Fab" user "Ref Des/Assembly Top")
		(33 "B.Fab" user "Ref Des/Assembly Bottom")
	)
	(footprint ""
		(layer "F.Cu")
		(at 196.654166 -255.560322 180)
		(property "Reference" "J99"
			(at -0.4318 -81.730088 0)
			(unlocked yes)
			(layer "F.SilkS")
			(effects
				(font
					(size 0.7874 0.5842)
					(thickness 0.1524)
				)
			)
		)
		(property "Value" ""
			(at 0 0 180)
			(layer "F.Fab")
			(effects
				(font
					(size 1.27 1.27)
				)
			)
		)
		(duplicate_pad_numbers_are_jumpers no)
		(pad "1" smd rect
			(at -2.050034 -63.324994 90)
			(size 0.519938 1.4986)
			(layers "F.Cu" "F.Mask" "F.Paste")
			(net "P12V_MEM_CPU1")
		)
		(pad "2" smd rect
			(at -2.050034 -62.47511 90)
			(size 0.519938 1.4986)
			(layers "F.Cu" "F.Mask" "F.Paste")
			(net "Net_2396")
		)
		(pad "3" smd rect
			(at -2.050034 -61.624972 90)
			(size 0.519938 1.4986)
			(layers "F.Cu" "F.Mask" "F.Paste")
			(net "P3V3_AUX")
		)
		(pad "4" smd rect
			(at -2.050034 -60.775088 90)
			(size 0.519938 1.4986)
			(layers "F.Cu" "F.Mask" "F.Paste")
			(net "I3C_SPD_DDRK_CPU1_SCL")
		)
		(pad "5" smd rect
			(at -2.050034 -59.92495 90)
			(size 0.519938 1.4986)
			(layers "F.Cu" "F.Mask" "F.Paste")
			(net "I3C_SPD_DDRK_CPU1_SDA")
		)
		(pad "6" smd rect
			(at -2.050034 -59.075066 90)
			(size 0.519938 1.4986)
			(layers "F.Cu" "F.Mask" "F.Paste")
			(net "GND")
		)
		(pad "7" smd rect
			(at -2.050034 -58.224928 90)
			(size 0.519938 1.4986)
			(layers "F.Cu" "F.Mask" "F.Paste")
			(net "M_K_CPU1_SA_DQ<0>")
		)
		(pad "8" smd rect
			(at -2.050034 -57.375044 90)
			(size 0.519938 1.4986)
			(layers "F.Cu" "F.Mask" "F.Paste")
			(net "GND")
		)
		(pad "9" smd rect
			(at -2.050034 -56.524906 90)
			(size 0.519938 1.4986)
			(layers "F.Cu" "F.Mask" "F.Paste")
			(net "M_K_CPU1_SA_DQ<1>")
		)
		(pad "10" smd rect
			(at -2.050034 -55.675022 90)
			(size 0.519938 1.4986)
			(layers "F.Cu" "F.Mask" "F.Paste")
			(net "GND")
		)
		(pad "11" smd rect
			(at -2.050034 -54.824884 90)
			(size 0.519938 1.4986)
			(layers "F.Cu" "F.Mask" "F.Paste")
			(net "M_K_CPU1_SA_DQS_DP<0>")
		)
		(pad "12" smd rect
			(at -2.050034 -53.975 90)
			(size 0.519938 1.4986)
			(layers "F.Cu" "F.Mask" "F.Paste")
			(net "M_K_CPU1_SA_DQS_DN<0>")
		)
		(pad "13" smd rect
			(at -2.050034 -53.125116 90)
			(size 0.519938 1.4986)
			(layers "F.Cu" "F.Mask" "F.Paste")
			(net "GND")
		)
		(pad "14" smd rect
			(at -2.050034 -52.274978 90)
			(size 0.519938 1.4986)
			(layers "F.Cu" "F.Mask" "F.Paste")
			(net "M_K_CPU1_SA_DQ<4>")
		)
		(pad "15" smd rect
			(at -2.050034 -51.425094 90)
			(size 0.519938 1.4986)
			(layers "F.Cu" "F.Mask" "F.Paste")
			(net "GND")
		)
		(pad "16" smd rect
			(at -2.050034 -50.574956 90)
			(size 0.519938 1.4986)
			(layers "F.Cu" "F.Mask" "F.Paste")
			(net "M_K_CPU1_SA_DQ<5>")
		)
		(pad "17" smd rect
			(at -2.050034 -49.725072 90)
			(size 0.519938 1.4986)
			(layers "F.Cu" "F.Mask" "F.Paste")
			(net "GND")
		)
		(pad "18" smd rect
			(at -2.050034 -48.874934 90)
			(size 0.519938 1.4986)
			(layers "F.Cu" "F.Mask" "F.Paste")
			(net "M_K_CPU1_SA_DQ<8>")
		)
		(pad "19" smd rect
			(at -2.050034 -48.02505 90)
			(size 0.519938 1.4986)
			(layers "F.Cu" "F.Mask" "F.Paste")
			(net "GND")
		)
		(pad "20" smd rect
			(at -2.050034 -47.174912 90)
			(size 0.519938 1.4986)
			(layers "F.Cu" "F.Mask" "F.Paste")
			(net "M_K_CPU1_SA_DQ<9>")
		)
		(pad "21" smd rect
			(at -2.050034 -46.325028 90)
			(size 0.519938 1.4986)
			(layers "F.Cu" "F.Mask" "F.Paste")
			(net "GND")
		)
		(pad "22" smd rect
			(at -2.050034 -45.47489 90)
			(size 0.519938 1.4986)
			(layers "F.Cu" "F.Mask" "F.Paste")
			(net "M_K_CPU1_SA_DQS_DP<1>")
		)
		(pad "23" smd rect
			(at -2.050034 -44.625006 90)
			(size 0.519938 1.4986)
			(layers "F.Cu" "F.Mask" "F.Paste")
			(net "M_K_CPU1_SA_DQS_DN<1>")
		)
		(pad "24" smd rect
			(at -2.050034 -43.775122 90)
			(size 0.519938 1.4986)
			(layers "F.Cu" "F.Mask" "F.Paste")
			(net "GND")
		)
		(pad "25" smd rect
			(at -2.050034 -42.924984 90)
			(size 0.519938 1.4986)
			(layers "F.Cu" "F.Mask" "F.Paste")
			(net "M_K_CPU1_SA_DQ<12>")
		)
		(pad "26" smd rect
			(at -2.050034 -42.0751 90)
			(size 0.519938 1.4986)
			(layers "F.Cu" "F.Mask" "F.Paste")
			(net "GND")
		)
		(pad "27" smd rect
			(at -2.050034 -41.224962 90)
			(size 0.519938 1.4986)
			(layers "F.Cu" "F.Mask" "F.Paste")
			(net "M_K_CPU1_SA_DQ<13>")
		)
		(pad "28" smd rect
			(at -2.050034 -40.375078 90)
			(size 0.519938 1.4986)
			(layers "F.Cu" "F.Mask" "F.Paste")
			(net "GND")
		)
		(pad "29" smd rect
			(at -2.050034 -39.52494 90)
			(size 0.519938 1.4986)
			(layers "F.Cu" "F.Mask" "F.Paste")
			(net "M_K_CPU1_SA_DQ<16>")
		)
		(pad "30" smd rect
			(at -2.050034 -38.675056 90)
			(size 0.519938 1.4986)
			(layers "F.Cu" "F.Mask" "F.Paste")
			(net "GND")
		)
		(pad "31" smd rect
			(at -2.050034 -37.824918 90)
			(size 0.519938 1.4986)
			(layers "F.Cu" "F.Mask" "F.Paste")
			(net "M_K_CPU1_SA_DQ<17>")
		)
		(pad "32" smd rect
			(at -2.050034 -36.975034 90)
			(size 0.519938 1.4986)
			(layers "F.Cu" "F.Mask" "F.Paste")
			(net "GND")
		)
		(pad "33" smd rect
			(at -2.050034 -36.124896 90)
			(size 0.519938 1.4986)
			(layers "F.Cu" "F.Mask" "F.Paste")
			(net "M_K_CPU1_SA_DQS_DP<2>")
		)
		(pad "34" smd rect
			(at -2.050034 -35.275012 90)
			(size 0.519938 1.4986)
			(layers "F.Cu" "F.Mask" "F.Paste")
			(net "M_K_CPU1_SA_DQS_DN<2>")
		)
		(pad "35" smd rect
			(at -2.050034 -34.425128 90)
			(size 0.519938 1.4986)
			(layers "F.Cu" "F.Mask" "F.Paste")
			(net "GND")
		)
		(pad "36" smd rect
			(at -2.050034 -33.57499 90)
			(size 0.519938 1.4986)
			(layers "F.Cu" "F.Mask" "F.Paste")
			(net "M_K_CPU1_SA_DQ<20>")
		)
		(pad "37" smd rect
			(at -2.050034 -32.725106 90)
			(size 0.519938 1.4986)
			(layers "F.Cu" "F.Mask" "F.Paste")
			(net "GND")
		)
		(pad "38" smd rect
			(at -2.050034 -31.874968 90)
			(size 0.519938 1.4986)
			(layers "F.Cu" "F.Mask" "F.Paste")
			(net "M_K_CPU1_SA_DQ<21>")
		)
		(pad "39" smd rect
			(at -2.050034 -31.025084 90)
			(size 0.519938 1.4986)
			(layers "F.Cu" "F.Mask" "F.Paste")
			(net "GND")
		)
		(pad "40" smd rect
			(at -2.050034 -30.174946 90)
			(size 0.519938 1.4986)
			(layers "F.Cu" "F.Mask" "F.Paste")
			(net "M_K_CPU1_SA_DQ<24>")
		)
		(pad "41" smd rect
			(at -2.050034 -29.325062 90)
			(size 0.519938 1.4986)
			(layers "F.Cu" "F.Mask" "F.Paste")
			(net "GND")
		)
		(pad "42" smd rect
			(at -2.050034 -28.474924 90)
			(size 0.519938 1.4986)
			(layers "F.Cu" "F.Mask" "F.Paste")
			(net "M_K_CPU1_SA_DQ<25>")
		)
		(pad "43" smd rect
			(at -2.050034 -27.62504 90)
			(size 0.519938 1.4986)
			(layers "F.Cu" "F.Mask" "F.Paste")
			(net "GND")
		)
		(pad "44" smd rect
			(at -2.050034 -26.774902 90)
			(size 0.519938 1.4986)
			(layers "F.Cu" "F.Mask" "F.Paste")
			(net "M_K_CPU1_SA_DQS_DP<3>")
		)
		(pad "45" smd rect
			(at -2.050034 -25.925018 90)
			(size 0.519938 1.4986)
			(layers "F.Cu" "F.Mask" "F.Paste")
			(net "M_K_CPU1_SA_DQS_DN<3>")
		)
		(pad "46" smd rect
			(at -2.050034 -25.07488 90)
			(size 0.519938 1.4986)
			(layers "F.Cu" "F.Mask" "F.Paste")
			(net "GND")
		)
		(pad "47" smd rect
			(at -2.050034 -24.224996 90)
			(size 0.519938 1.4986)
			(layers "F.Cu" "F.Mask" "F.Paste")
			(net "M_K_CPU1_SA_DQ<28>")
		)
		(pad "48" smd rect
			(at -2.050034 -23.375112 90)
			(size 0.519938 1.4986)
			(layers "F.Cu" "F.Mask" "F.Paste")
			(net "GND")
		)
		(pad "49" smd rect
			(at -2.050034 -22.524974 90)
			(size 0.519938 1.4986)
			(layers "F.Cu" "F.Mask" "F.Paste")
			(net "M_K_CPU1_SA_DQ<29>")
		)
		(pad "50" smd rect
			(at -2.050034 -21.67509 90)
			(size 0.519938 1.4986)
			(layers "F.Cu" "F.Mask" "F.Paste")
			(net "GND")
		)
		(pad "51" smd rect
			(at -2.050034 -20.824952 90)
			(size 0.519938 1.4986)
			(layers "F.Cu" "F.Mask" "F.Paste")
			(net "M_K_CPU1_SA_CB<0>")
		)
		(pad "52" smd rect
			(at -2.050034 -19.975068 90)
			(size 0.519938 1.4986)
			(layers "F.Cu" "F.Mask" "F.Paste")
			(net "GND")
		)
		(pad "53" smd rect
			(at -2.050034 -19.12493 90)
			(size 0.519938 1.4986)
			(layers "F.Cu" "F.Mask" "F.Paste")
			(net "M_K_CPU1_SA_CB<1>")
		)
		(pad "54" smd rect
			(at -2.050034 -18.275046 90)
			(size 0.519938 1.4986)
			(layers "F.Cu" "F.Mask" "F.Paste")
			(net "GND")
		)
		(pad "55" smd rect
			(at -2.050034 -17.424908 90)
			(size 0.519938 1.4986)
			(layers "F.Cu" "F.Mask" "F.Paste")
			(net "M_K_CPU1_SA_DQS_DP<4>")
		)
		(pad "56" smd rect
			(at -2.050034 -16.575024 90)
			(size 0.519938 1.4986)
			(layers "F.Cu" "F.Mask" "F.Paste")
			(net "M_K_CPU1_SA_DQS_DN<4>")
		)
		(pad "57" smd rect
			(at -2.050034 -15.724886 90)
			(size 0.519938 1.4986)
			(layers "F.Cu" "F.Mask" "F.Paste")
			(net "GND")
		)
		(pad "58" smd rect
			(at -2.050034 -14.875002 90)
			(size 0.519938 1.4986)
			(layers "F.Cu" "F.Mask" "F.Paste")
			(net "M_K_CPU1_SA_CB<4>")
		)
		(pad "59" smd rect
			(at -2.050034 -14.025118 90)
			(size 0.519938 1.4986)
			(layers "F.Cu" "F.Mask" "F.Paste")
			(net "GND")
		)
		(pad "60" smd rect
			(at -2.050034 -13.17498 90)
			(size 0.519938 1.4986)
			(layers "F.Cu" "F.Mask" "F.Paste")
			(net "M_K_CPU1_SA_CB<5>")
		)
		(pad "61" smd rect
			(at -2.050034 -12.325096 90)
			(size 0.519938 1.4986)
			(layers "F.Cu" "F.Mask" "F.Paste")
			(net "GND")
		)
		(pad "62" smd rect
			(at -2.050034 -11.474958 90)
			(size 0.519938 1.4986)
			(layers "F.Cu" "F.Mask" "F.Paste")
			(net "M_K_CPU1_ALERT_N")
		)
		(pad "63" smd rect
			(at -2.050034 -10.625074 90)
			(size 0.519938 1.4986)
			(layers "F.Cu" "F.Mask" "F.Paste")
			(net "GND")
		)
		(pad "64" smd rect
			(at -2.050034 -9.774936 90)
			(size 0.519938 1.4986)
			(layers "F.Cu" "F.Mask" "F.Paste")
			(net "M_K_CPU1_SA_CS_N<0>")
		)
		(pad "65" smd rect
			(at -2.050034 -8.925052 90)
			(size 0.519938 1.4986)
			(layers "F.Cu" "F.Mask" "F.Paste")
			(net "GND")
		)
		(pad "66" smd rect
			(at -2.050034 -8.074914 90)
			(size 0.519938 1.4986)
			(layers "F.Cu" "F.Mask" "F.Paste")
			(net "M_K_CPU1_SA_CA<0>")
		)
		(pad "67" smd rect
			(at -2.050034 -7.22503 90)
			(size 0.519938 1.4986)
			(layers "F.Cu" "F.Mask" "F.Paste")
			(net "GND")
		)
		(pad "68" smd rect
			(at -2.050034 -6.374892 90)
			(size 0.519938 1.4986)
			(layers "F.Cu" "F.Mask" "F.Paste")
			(net "M_K_CPU1_SA_CA<2>")
		)
		(pad "69" smd rect
			(at -2.050034 -5.525008 90)
			(size 0.519938 1.4986)
			(layers "F.Cu" "F.Mask" "F.Paste")
			(net "GND")
		)
		(pad "70" smd rect
			(at -2.050034 -4.675124 90)
			(size 0.519938 1.4986)
			(layers "F.Cu" "F.Mask" "F.Paste")
			(net "M_K_CPU1_SA_CA<4>")
		)
		(pad "71" smd rect
			(at -2.050034 -3.824986 90)
			(size 0.519938 1.4986)
			(layers "F.Cu" "F.Mask" "F.Paste")
			(net "GND")
		)
		(pad "72" smd rect
			(at -2.050034 -2.975102 90)
			(size 0.519938 1.4986)
			(layers "F.Cu" "F.Mask" "F.Paste")
			(net "M_K_CPU1_SA_CA<6>")
		)
		(pad "73" smd rect
			(at -2.050034 -2.124964 90)
			(size 0.519938 1.4986)
			(layers "F.Cu" "F.Mask" "F.Paste")
			(net "GND")
		)
		(pad "74" smd rect
			(at -2.050034 -1.27508 90)
			(size 0.519938 1.4986)
			(layers "F.Cu" "F.Mask" "F.Paste")
			(net "M_K_CPU1_SA_PAR")
		)
		(pad "75" smd rect
			(at -2.050034 -0.424942 90)
			(size 0.519938 1.4986)
			(layers "F.Cu" "F.Mask" "F.Paste")
			(net "GND")
		)
		(pad "76" smd rect
			(at -2.050034 5.525008 90)
			(size 0.519938 1.4986)
			(layers "F.Cu" "F.Mask" "F.Paste")
			(net "M_K_CPU1_SB_CA<0>")
		)
		(pad "77" smd rect
			(at -2.050034 6.374892 90)
			(size 0.519938 1.4986)
			(layers "F.Cu" "F.Mask" "F.Paste")
			(net "GND")
		)
		(pad "78" smd rect
			(at -2.050034 7.22503 90)
			(size 0.519938 1.4986)
			(layers "F.Cu" "F.Mask" "F.Paste")
			(net "M_K_CPU1_SB_CA<2>")
		)
		(pad "79" smd rect
			(at -2.050034 8.074914 90)
			(size 0.519938 1.4986)
			(layers "F.Cu" "F.Mask" "F.Paste")
			(net "GND")
		)
		(pad "80" smd rect
			(at -2.050034 8.925052 90)
			(size 0.519938 1.4986)
			(layers "F.Cu" "F.Mask" "F.Paste")
			(net "M_K_CPU1_SB_CA<4>")
		)
		(pad "81" smd rect
			(at -2.050034 9.774936 90)
			(size 0.519938 1.4986)
			(layers "F.Cu" "F.Mask" "F.Paste")
			(net "GND")
		)
		(pad "82" smd rect
			(at -2.050034 10.625074 90)
			(size 0.519938 1.4986)
			(layers "F.Cu" "F.Mask" "F.Paste")
			(net "M_K_CPU1_SB_CA<6>")
		)
		(pad "83" smd rect
			(at -2.050034 11.474958 90)
			(size 0.519938 1.4986)
			(layers "F.Cu" "F.Mask" "F.Paste")
			(net "GND")
		)
		(pad "84" smd rect
			(at -2.050034 12.325096 90)
			(size 0.519938 1.4986)
			(layers "F.Cu" "F.Mask" "F.Paste")
			(net "M_K_CPU1_SB_CS_N<0>")
		)
		(pad "85" smd rect
			(at -2.050034 13.17498 90)
			(size 0.519938 1.4986)
			(layers "F.Cu" "F.Mask" "F.Paste")
			(net "GND")
		)
		(pad "86" smd rect
			(at -2.050034 14.025118 90)
			(size 0.519938 1.4986)
			(layers "F.Cu" "F.Mask" "F.Paste")
			(net "M_K_CPU1_SA_RSP<0>")
		)
		(pad "87" smd rect
			(at -2.050034 14.875002 90)
			(size 0.519938 1.4986)
			(layers "F.Cu" "F.Mask" "F.Paste")
			(net "M_K_CPU1_SB_RSP<0>")
		)
		(pad "88" smd rect
			(at -2.050034 15.724886 90)
			(size 0.519938 1.4986)
			(layers "F.Cu" "F.Mask" "F.Paste")
			(net "GND")
		)
		(pad "89" smd rect
			(at -2.050034 16.575024 90)
			(size 0.519938 1.4986)
			(layers "F.Cu" "F.Mask" "F.Paste")
			(net "M_K_CPU1_SB_CB<4>")
		)
		(pad "90" smd rect
			(at -2.050034 17.424908 90)
			(size 0.519938 1.4986)
			(layers "F.Cu" "F.Mask" "F.Paste")
			(net "GND")
		)
		(pad "91" smd rect
			(at -2.050034 18.275046 90)
			(size 0.519938 1.4986)
			(layers "F.Cu" "F.Mask" "F.Paste")
			(net "M_K_CPU1_SB_CB<5>")
		)
		(pad "92" smd rect
			(at -2.050034 19.12493 90)
			(size 0.519938 1.4986)
			(layers "F.Cu" "F.Mask" "F.Paste")
			(net "GND")
		)
		(pad "93" smd rect
			(at -2.050034 19.975068 90)
			(size 0.519938 1.4986)
			(layers "F.Cu" "F.Mask" "F.Paste")
			(net "M_K_CPU1_SB_DQS_DP<9>")
		)
		(pad "94" smd rect
			(at -2.050034 20.824952 90)
			(size 0.519938 1.4986)
			(layers "F.Cu" "F.Mask" "F.Paste")
			(net "M_K_CPU1_SB_DQS_DN<9>")
		)
		(pad "95" smd rect
			(at -2.050034 21.67509 90)
			(size 0.519938 1.4986)
			(layers "F.Cu" "F.Mask" "F.Paste")
			(net "GND")
		)
		(pad "96" smd rect
			(at -2.050034 22.524974 90)
			(size 0.519938 1.4986)
			(layers "F.Cu" "F.Mask" "F.Paste")
			(net "M_K_CPU1_SB_CB<0>")
		)
		(pad "97" smd rect
			(at -2.050034 23.375112 90)
			(size 0.519938 1.4986)
			(layers "F.Cu" "F.Mask" "F.Paste")
			(net "GND")
		)
		(pad "98" smd rect
			(at -2.050034 24.224996 90)
			(size 0.519938 1.4986)
			(layers "F.Cu" "F.Mask" "F.Paste")
			(net "M_K_CPU1_SB_CB<1>")
		)
		(pad "99" smd rect
			(at -2.050034 25.07488 90)
			(size 0.519938 1.4986)
			(layers "F.Cu" "F.Mask" "F.Paste")
			(net "GND")
		)
		(pad "100" smd rect
			(at -2.050034 25.925018 90)
			(size 0.519938 1.4986)
			(layers "F.Cu" "F.Mask" "F.Paste")
			(net "M_K_CPU1_SB_DQ<0>")
		)
		(pad "101" smd rect
			(at -2.050034 26.774902 90)
			(size 0.519938 1.4986)
			(layers "F.Cu" "F.Mask" "F.Paste")
			(net "GND")
		)
		(pad "102" smd rect
			(at -2.050034 27.62504 90)
			(size 0.519938 1.4986)
			(layers "F.Cu" "F.Mask" "F.Paste")
			(net "M_K_CPU1_SB_DQ<1>")
		)
		(pad "103" smd rect
			(at -2.050034 28.474924 90)
			(size 0.519938 1.4986)
			(layers "F.Cu" "F.Mask" "F.Paste")
			(net "GND")
		)
		(pad "104" smd rect
			(at -2.050034 29.325062 90)
			(size 0.519938 1.4986)
			(layers "F.Cu" "F.Mask" "F.Paste")
			(net "M_K_CPU1_SB_DQS_DP<0>")
		)
		(pad "105" smd rect
			(at -2.050034 30.174946 90)
			(size 0.519938 1.4986)
			(layers "F.Cu" "F.Mask" "F.Paste")
			(net "M_K_CPU1_SB_DQS_DN<0>")
		)
		(pad "106" smd rect
			(at -2.050034 31.025084 90)
			(size 0.519938 1.4986)
			(layers "F.Cu" "F.Mask" "F.Paste")
			(net "GND")
		)
		(pad "107" smd rect
			(at -2.050034 31.874968 90)
			(size 0.519938 1.4986)
			(layers "F.Cu" "F.Mask" "F.Paste")
			(net "M_K_CPU1_SB_DQ<4>")
		)
		(pad "108" smd rect
			(at -2.050034 32.725106 90)
			(size 0.519938 1.4986)
			(layers "F.Cu" "F.Mask" "F.Paste")
			(net "GND")
		)
		(pad "109" smd rect
			(at -2.050034 33.57499 90)
			(size 0.519938 1.4986)
			(layers "F.Cu" "F.Mask" "F.Paste")
			(net "M_K_CPU1_SB_DQ<5>")
		)
		(pad "110" smd rect
			(at -2.050034 34.425128 90)
			(size 0.519938 1.4986)
			(layers "F.Cu" "F.Mask" "F.Paste")
			(net "GND")
		)
		(pad "111" smd rect
			(at -2.050034 35.275012 90)
			(size 0.519938 1.4986)
			(layers "F.Cu" "F.Mask" "F.Paste")
			(net "M_K_CPU1_SB_DQ<8>")
		)
		(pad "112" smd rect
			(at -2.050034 36.124896 90)
			(size 0.519938 1.4986)
			(layers "F.Cu" "F.Mask" "F.Paste")
			(net "GND")
		)
		(pad "113" smd rect
			(at -2.050034 36.975034 90)
			(size 0.519938 1.4986)
			(layers "F.Cu" "F.Mask" "F.Paste")
			(net "M_K_CPU1_SB_DQ<9>")
		)
	)
)
